#ISCELL
  pure_quanta quanta_title_block_c *
  *
#CELL
  pure_quanta q_led *
  page142_i79
#CELL
  pure_quanta mosfet_n_gsd *
  page142_i80
#CELL
  pure_quanta mosfet_n_gsd *
  page142_i81
#CELL
  pure_quanta q_res *
  page142_i82
#ISCELL
  pure_quanta_power universal_power *
  page142_i83
#ISCELL
  pure_quanta_power universal_gnd *
  page142_i85
#ISCELL
  pure_quanta_power universal_power *
  page142_i86
#CELL
  pure_quanta q_res *
  page142_i87
#ISCELL
  standard offpage *
  page142_i88
